# S9S_MB_2U (Grand Teton) — schematic netlist excerpt (pin names and nets, part order shuffled) for the footprints in the layout excerpt that follows; sources: Cadence DE-HDL packaged netlist, KiCad conversion of 03242023_DA0F0TMBIJ0_F0T_Motherboard_J_brd_V01_OCP.brd

C523  Q_CAP  47UF 4V 20% X6S  pkg C0805  page 76 : A = PVCCFA_EHV_FIVRA_CPU0 ; B = GND
PR255  Q_RES  2.2 1% CHIP  pkg 0402LF  page 293 : A = PVCCFA_EHV_CPU1_PVCC ; B = PVCCINFAON_CPU1_VDD2
R36  Q_RES  23.2K 1% CHIP  pkg 0402LF  page 92 : A = PD_CHF_CPU0_DIMM1_SAA ; B = GND

(kicad_pcb
	(version 20260206)
	(generator "pcbnew")
	(generator_version "10.0")
	(general
		(thickness 1.6)
		(legacy_teardrops no)
	)
	(paper "A4")
	(title_block
		(title "03242023_DA0F0TMBIJ0_F0T_Motherboard_J_brd_V01_OCP.brd")
		(comment 1 "Grand Teton / footprints 5711-5713 of 6105")
	)
	(layers
		(0 "F.Cu" signal "TOP")
		(4 "In1.Cu" signal "GND")
		(6 "In2.Cu" signal "IN1")
		(8 "In3.Cu" signal "GND1")
		(10 "In4.Cu" signal "IN2")
		(12 "In5.Cu" signal "GND2")
		(14 "In6.Cu" signal "IN3")
		(16 "In7.Cu" signal "GND3")
		(18 "In8.Cu" signal "VCC")
		(20 "In9.Cu" signal "VCC1")
		(22 "In10.Cu" signal "GND4")
		(24 "In11.Cu" signal "IN4")
		(26 "In12.Cu" signal "GND5")
		(28 "In13.Cu" signal "IN5")
		(30 "In14.Cu" signal "GND6")
		(32 "In15.Cu" signal "IN6")
		(34 "In16.Cu" signal "GND7")
		(2 "B.Cu" signal "BOTTOM")
		(9 "F.Adhes" user "F.Adhesive")
		(11 "B.Adhes" user "B.Adhesive")
		(13 "F.Paste" user "Package Geometry/Pastemask Top")
		(15 "B.Paste" user "Package Geometry/Pastemask Bottom")
		(5 "F.SilkS" user "Ref Des/Silkscreen Top")
		(7 "B.SilkS" user "Ref Des/Silkscreen Bottom")
		(1 "F.Mask" user "Board Geometry/Soldermask Top")
		(3 "B.Mask" user "Board Geometry/Soldermask Bottom")
		(17 "Dwgs.User" user "User.Drawings")
		(19 "Cmts.User" user "User.Comments")
		(21 "Eco1.User" user "User.Eco1")
		(23 "Eco2.User" user "User.Eco2")
		(25 "Edge.Cuts" user "Board Geometry/Outline")
		(27 "Margin" user)
		(31 "F.CrtYd" user "Package Geometry/Place Bound Top")
		(29 "B.CrtYd" user "Package Geometry/Place Bound Bottom")
		(35 "F.Fab" user "Ref Des/Assembly Top")
		(33 "B.Fab" user "Ref Des/Assembly Bottom")
	)
	(footprint ""
		(layer "B.Cu")
		(at 53.912516 -145.445226)
		(property "Reference" "PR255"
			(at 0 0 0)
			(layer "B.SilkS")
			(hide yes)
			(effects
				(font
					(size 1.27 1.27)
				)
				(justify mirror)
			)
		)
		(property "Value" ""
			(at 0 0 0)
			(layer "B.Fab")
			(effects
				(font
					(size 1.27 1.27)
				)
				(justify mirror)
			)
		)
		(duplicate_pad_numbers_are_jumpers no)
		(fp_line
			(start -0.7874 -0.4064)
			(end -0.7874 0.4064)
			(stroke
				(width 0.1524)
				(type default)
			)
			(layer "B.SilkS")
		)
		(fp_line
			(start -0.7874 0.4064)
			(end 0.7874 0.4064)
			(stroke
				(width 0.1524)
				(type default)
			)
			(layer "B.SilkS")
		)
		(fp_line
			(start 0.7874 -0.4064)
			(end -0.7874 -0.4064)
			(stroke
				(width 0.1524)
				(type default)
			)
			(layer "B.SilkS")
		)
		(fp_line
			(start 0.7874 0.4064)
			(end 0.7874 -0.4064)
			(stroke
				(width 0.1524)
				(type default)
			)
			(layer "B.SilkS")
		)
		(fp_line
			(start -0.67945 -0.3048)
			(end -0.67945 0.3048)
			(stroke
				(width 0.1)
				(type default)
			)
			(layer "B.Fab")
		)
		(fp_line
			(start -0.67945 0.3048)
			(end -0.120396 0.3048)
			(stroke
				(width 0.1)
				(type default)
			)
			(layer "B.Fab")
		)
		(fp_line
			(start -0.12065 -0.3048)
			(end -0.67945 -0.3048)
			(stroke
				(width 0.1)
				(type default)
			)
			(layer "B.Fab")
		)
		(fp_line
			(start -0.12065 -0.2794)
			(end -0.12065 -0.3048)
			(stroke
				(width 0.1)
				(type default)
			)
			(layer "B.Fab")
		)
		(fp_line
			(start -0.120396 0.2794)
			(end 0.12065 0.2794)
			(stroke
				(width 0.1)
				(type default)
			)
			(layer "B.Fab")
		)
		(fp_line
			(start -0.120396 0.3048)
			(end -0.120396 0.2794)
			(stroke
				(width 0.1)
				(type default)
			)
			(layer "B.Fab")
		)
		(fp_line
			(start 0.12065 -0.305054)
			(end 0.12065 -0.2794)
			(stroke
				(width 0.1)
				(type default)
			)
			(layer "B.Fab")
		)
		(fp_line
			(start 0.12065 -0.2794)
			(end -0.12065 -0.2794)
			(stroke
				(width 0.1)
				(type default)
			)
			(layer "B.Fab")
		)
		(fp_line
			(start 0.12065 0.2794)
			(end 0.12065 0.3048)
			(stroke
				(width 0.1)
				(type default)
			)
			(layer "B.Fab")
		)
		(fp_line
			(start 0.12065 0.3048)
			(end 0.67945 0.3048)
			(stroke
				(width 0.1)
				(type default)
			)
			(layer "B.Fab")
		)
		(fp_line
			(start 0.67945 -0.305054)
			(end 0.12065 -0.305054)
			(stroke
				(width 0.1)
				(type default)
			)
			(layer "B.Fab")
		)
		(fp_line
			(start 0.67945 0.3048)
			(end 0.67945 -0.305054)
			(stroke
				(width 0.1)
				(type default)
			)
			(layer "B.Fab")
		)
		(pad "1" smd circle
			(at 0.40005 0 180)
			(size 0 0)
			(layers "B.Cu" "B.Mask" "B.Paste")
			(net "PVCCFA_EHV_CPU1_PVCC")
		)
		(pad "2" smd circle
			(at -0.40005 0 180)
			(size 0 0)
			(layers "B.Cu" "B.Mask" "B.Paste")
			(net "PVCCINFAON_CPU1_VDD2")
		)
	)
	(footprint ""
		(layer "B.Cu")
		(at 310.957214 -258.379976 -90)
		(property "Reference" "C523"
			(at 0 0 90)
			(layer "B.SilkS")
			(hide yes)
			(effects
				(font
					(size 1.27 1.27)
				)
				(justify mirror)
			)
		)
		(property "Value" ""
			(at 0 0 90)
			(layer "B.Fab")
			(effects
				(font
					(size 1.27 1.27)
				)
				(justify mirror)
			)
		)
		(duplicate_pad_numbers_are_jumpers no)
		(fp_line
			(start -1.524 0.762)
			(end 1.524 0.762)
			(stroke
				(width 0.1524)
				(type default)
			)
			(layer "B.SilkS")
		)
		(fp_line
			(start 1.524 0.762)
			(end 1.524 -0.762)
			(stroke
				(width 0.1524)
				(type default)
			)
			(layer "B.SilkS")
		)
		(fp_line
			(start -1.524 -0.762)
			(end -1.524 0.762)
			(stroke
				(width 0.1524)
				(type default)
			)
			(layer "B.SilkS")
		)
		(fp_line
			(start 1.524 -0.762)
			(end -1.524 -0.762)
			(stroke
				(width 0.1524)
				(type default)
			)
			(layer "B.SilkS")
		)
		(fp_line
			(start -1.1049 0.724916)
			(end -1.1049 -0.724916)
			(stroke
				(width 0.1)
				(type default)
			)
			(layer "B.Fab")
		)
		(fp_line
			(start 1.1049 0.724916)
			(end -1.1049 0.724916)
			(stroke
				(width 0.1)
				(type default)
			)
			(layer "B.Fab")
		)
		(fp_line
			(start -1.1049 -0.724916)
			(end 1.1049 -0.724916)
			(stroke
				(width 0.1)
				(type default)
			)
			(layer "B.Fab")
		)
		(fp_line
			(start 1.1049 -0.724916)
			(end 1.1049 0.724916)
			(stroke
				(width 0.1)
				(type default)
			)
			(layer "B.Fab")
		)
		(pad "1" smd rect
			(at 0.889 0 270)
			(size 1.016 1.27)
			(layers "B.Cu" "B.Mask" "B.Paste")
			(net "PVCCFA_EHV_FIVRA_CPU0")
		)
		(pad "2" smd rect
			(at -0.889 0 270)
			(size 1.016 1.27)
			(layers "B.Cu" "B.Mask" "B.Paste")
			(net "GND")
		)
	)
	(footprint ""
		(layer "B.Cu")
		(at 431.168556 -318.577976)
		(property "Reference" "R36"
			(at 0 0 0)
			(layer "B.SilkS")
			(hide yes)
			(effects
				(font
					(size 1.27 1.27)
				)
				(justify mirror)
			)
		)
		(property "Value" ""
			(at 0 0 0)
			(layer "B.Fab")
			(effects
				(font
					(size 1.27 1.27)
				)
				(justify mirror)
			)
		)
		(duplicate_pad_numbers_are_jumpers no)
		(fp_line
			(start -0.7874 -0.4064)
			(end -0.7874 0.4064)
			(stroke
				(width 0.1524)
				(type default)
			)
			(layer "B.SilkS")
		)
		(fp_line
			(start -0.7874 0.4064)
			(end 0.7874 0.4064)
			(stroke
				(width 0.1524)
				(type default)
			)
			(layer "B.SilkS")
		)
		(fp_line
			(start 0.7874 -0.4064)
			(end -0.7874 -0.4064)
			(stroke
				(width 0.1524)
				(type default)
			)
			(layer "B.SilkS")
		)
		(fp_line
			(start 0.7874 0.4064)
			(end 0.7874 -0.4064)
			(stroke
				(width 0.1524)
				(type default)
			)
			(layer "B.SilkS")
		)
		(fp_line
			(start -0.67945 -0.3048)
			(end -0.67945 0.3048)
			(stroke
				(width 0.1)
				(type default)
			)
			(layer "B.Fab")
		)
		(fp_line
			(start -0.67945 0.3048)
			(end -0.120396 0.3048)
			(stroke
				(width 0.1)
				(type default)
			)
			(layer "B.Fab")
		)
		(fp_line
			(start -0.12065 -0.3048)
			(end -0.67945 -0.3048)
			(stroke
				(width 0.1)
				(type default)
			)
			(layer "B.Fab")
		)
		(fp_line
			(start -0.12065 -0.2794)
			(end -0.12065 -0.3048)
			(stroke
				(width 0.1)
				(type default)
			)
			(layer "B.Fab")
		)
		(fp_line
			(start -0.120396 0.2794)
			(end 0.12065 0.2794)
			(stroke
				(width 0.1)
				(type default)
			)
			(layer "B.Fab")
		)
		(fp_line
			(start -0.120396 0.3048)
			(end -0.120396 0.2794)
			(stroke
				(width 0.1)
				(type default)
			)
			(layer "B.Fab")
		)
		(fp_line
			(start 0.12065 -0.305054)
			(end 0.12065 -0.2794)
			(stroke
				(width 0.1)
				(type default)
			)
			(layer "B.Fab")
		)
		(fp_line
			(start 0.12065 -0.2794)
			(end -0.12065 -0.2794)
			(stroke
				(width 0.1)
				(type default)
			)
			(layer "B.Fab")
		)
		(fp_line
			(start 0.12065 0.2794)
			(end 0.12065 0.3048)
			(stroke
				(width 0.1)
				(type default)
			)
			(layer "B.Fab")
		)
		(fp_line
			(start 0.12065 0.3048)
			(end 0.67945 0.3048)
			(stroke
				(width 0.1)
				(type default)
			)
			(layer "B.Fab")
		)
		(fp_line
			(start 0.67945 -0.305054)
			(end 0.12065 -0.305054)
			(stroke
				(width 0.1)
				(type default)
			)
			(layer "B.Fab")
		)
		(fp_line
			(start 0.67945 0.3048)
			(end 0.67945 -0.305054)
			(stroke
				(width 0.1)
				(type default)
			)
			(layer "B.Fab")
		)
		(pad "1" smd circle
			(at 0.40005 0 180)
			(size 0 0)
			(layers "B.Cu" "B.Mask" "B.Paste")
			(net "PD_CHF_CPU0_DIMM1_SAA")
		)
		(pad "2" smd circle
			(at -0.40005 0 180)
			(size 0 0)
			(layers "B.Cu" "B.Mask" "B.Paste")
			(net "GND")
		)
	)
)
